# S9S_MB_2U (Grand Teton) — schematic netlist excerpt (pin names and nets, part order shuffled) for the footprints in the layout excerpt that follows; sources: Cadence DE-HDL packaged netlist, KiCad conversion of 03242023_DA0F0TMBIJ0_F0T_Motherboard_J_brd_V01_OCP.brd

J12  SCONN288_ADR50017P087CC  SCONN288_ADR50017-P087CC IO  pkg DDR288S_1-1VXB  page 93
  VIN_BULK0  = P12V_S3_AUX_CPU0_NVDIMM
  RFU0  = TP_CHF_CPU0_DIMM2_FRU_0
  VIN_MGMT  = P3V3_AUX
  HSCL  = I3C_SPD_DDREFGH_CPU0_LVC1_SCL_3
  HSDA  = I3C_SPD_DDREFGH_CPU0_LVC1_SDA
  VSS0  = GND
  DQ0_A  = M_F_CPU0_SA_DQ<0>
  VSS1  = GND
  DQ1_A  = M_F_CPU0_SA_DQ<1>
  VSS2  = GND
  DQS0_A_T  = M_F_CPU0_SA_DQS_DP<0>
  DQS0_A_C  = M_F_CPU0_SA_DQS_DN<0>
  VSS3  = GND
  DQ4_A  = M_F_CPU0_SA_DQ<4>
  VSS4  = GND
  DQ5_A  = M_F_CPU0_SA_DQ<5>
  VSS5  = GND
  DQ8_A  = M_F_CPU0_SA_DQ<8>
  VSS6  = GND
  DQ9_A  = M_F_CPU0_SA_DQ<9>
  VSS7  = GND
  DQS1_A_T  = M_F_CPU0_SA_DQS_DP<1>
  DQS1_A_C  = M_F_CPU0_SA_DQS_DN<1>
  VSS8  = GND
  DQ12_A  = M_F_CPU0_SA_DQ<12>
  VSS9  = GND
  DQ13_A  = M_F_CPU0_SA_DQ<13>
  VSS10  = GND
  DQ16_A  = M_F_CPU0_SA_DQ<16>
  VSS11  = GND
  DQ17_A  = M_F_CPU0_SA_DQ<17>
  VSS12  = GND
  DQS2_A_T  = M_F_CPU0_SA_DQS_DP<2>
  DQS2_A_C  = M_F_CPU0_SA_DQS_DN<2>
  VSS13  = GND
  DQ20_A  = M_F_CPU0_SA_DQ<20>
  VSS14  = GND
  DQ21_A  = M_F_CPU0_SA_DQ<21>
  VSS15  = GND
  DQ24_A  = M_F_CPU0_SA_DQ<24>
  VSS16  = GND
  DQ25_A  = M_F_CPU0_SA_DQ<25>
  VSS17  = GND
  DQS3_A_T  = M_F_CPU0_SA_DQS_DP<3>
  DQS3_A_C  = M_F_CPU0_SA_DQS_DN<3>
  VSS18  = GND
  DQ28_A  = M_F_CPU0_SA_DQ<28>
  VSS19  = GND
  DQ29_A  = M_F_CPU0_SA_DQ<29>
  VSS20  = GND
  CB0_A  = M_F_CPU0_SA_CB<0>
  VSS21  = GND
  CB1_A  = M_F_CPU0_SA_CB<1>
  VSS22  = GND
  DQS4_A_T  = M_F_CPU0_SA_DQS_DP<4>
  DQS4_A_C  = M_F_CPU0_SA_DQS_DN<4>
  VSS23  = GND
  CB4_A  = M_F_CPU0_SA_CB<4>
  VSS24  = GND
  CB5_A  = M_F_CPU0_SA_CB<5>
  VSS25  = GND
  ALERT_N  = M_F_CPU0_ALERT_N
  VSS26  = GND
  CS0_A_N  = M_F_CPU0_SA_CS_N<2>
  VSS27  = GND
  CA0_A  = M_F_CPU0_SA_CA<0>
  VSS28  = GND
  CA2_A  = M_F_CPU0_SA_CA<2>
  VSS29  = GND
  CA4_A  = M_F_CPU0_SA_CA<4>
  VSS30  = GND
  CA6_A  = M_F_CPU0_SA_CA<6>
  VSS31  = GND
  PAR_A  = M_F_CPU0_SA_PAR
  VSS32  = GND
  CA0_B  = M_F_CPU0_SB_CA<0>
  VSS33  = GND
  CA2_B  = M_F_CPU0_SB_CA<2>
  VSS34  = GND
  CA4_B  = M_F_CPU0_SB_CA<4>
  VSS35  = GND
  CA6_B  = M_F_CPU0_SB_CA<6>
  VSS36  = GND
  CS0_B_N  = M_F_CPU0_SB_CS_N<2>
  VSS37  = GND
  \lbd||rsp_a_n\  = M_F_CPU0_SA_RSP<1>
  \lbs||rsp_b_n\  = M_F_CPU0_SB_RSP<1>
  VSS38  = GND
  CB4_B  = M_F_CPU0_SB_CB<4>
  VSS39  = GND
  CB5_B  = M_F_CPU0_SB_CB<5>
  VSS40  = GND
  \dqs9_b_t||tdqs9_b_t||dbi4_b_n\  = M_F_CPU0_SB_DQS_DP<9>
  \dqs9_b_c||tdqs9_b_c\  = M_F_CPU0_SB_DQS_DN<9>
  VSS41  = GND
  CB0_B  = M_F_CPU0_SB_CB<0>
  VSS42  = GND
  CB1_B  = M_F_CPU0_SB_CB<1>
  VSS43  = GND
  DQ0_B  = M_F_CPU0_SB_DQ<0>
  VSS44  = GND
  DQ1_B  = M_F_CPU0_SB_DQ<1>
  VSS45  = GND
  DQS0_B_T  = M_F_CPU0_SB_DQS_DP<0>
  DQS0_B_C  = M_F_CPU0_SB_DQS_DN<0>
  VSS46  = GND
  DQ4_B  = M_F_CPU0_SB_DQ<4>
  VSS47  = GND
  DQ5_B  = M_F_CPU0_SB_DQ<5>
  VSS48  = GND
  DQ8_B  = M_F_CPU0_SB_DQ<8>
  VSS49  = GND
  DQ9_B  = M_F_CPU0_SB_DQ<9>
  VSS50  = GND
  DQS1_B_T  = M_F_CPU0_SB_DQS_DP<1>
  DQS1_B_C  = M_F_CPU0_SB_DQS_DN<1>
  VSS51  = GND
  DQ12_B  = M_F_CPU0_SB_DQ<12>
  VSS52  = GND
  DQ13_B  = M_F_CPU0_SB_DQ<13>
  VSS53  = GND
  DQ16_B  = M_F_CPU0_SB_DQ<16>
  VSS54  = GND
  DQ17_B  = M_F_CPU0_SB_DQ<17>
  VSS55  = GND
  DQS2_B_T  = M_F_CPU0_SB_DQS_DP<2>
  DQS2_B_C  = M_F_CPU0_SB_DQS_DN<2>
  VSS56  = GND
  DQ20_B  = M_F_CPU0_SB_DQ<20>
  VSS57  = GND
  DQ21_B  = M_F_CPU0_SB_DQ<21>
  VSS58  = GND
  DQ24_B  = M_F_CPU0_SB_DQ<24>
  VSS59  = GND
  DQ25_B  = M_F_CPU0_SB_DQ<25>
  VSS60  = GND
  DQS3_B_T  = M_F_CPU0_SB_DQS_DP<3>
  DQS3_B_C  = M_F_CPU0_SB_DQS_DN<3>
  VSS61  = GND
  DQ28_B  = M_F_CPU0_SB_DQ<28>
  VSS62  = GND
  DQ29_B  = M_F_CPU0_SB_DQ<29>
  VSS63  = GND
  RFU1  = TP_CHF_CPU0_DIMM2_FRU_1
  VIN_BULK1  = P12V_S3_AUX_CPU0_NVDIMM
  VIN_BULK2  = P12V_S3_AUX_CPU0_NVDIMM
  \pwr_good||fail_n\  = PWRGD_CHF_CPU0_DIMM2
  HSA  = PD_CHF_CPU0_DIMM2_SAA
  RFU2  = TP_CHF_CPU0_DIMM2_FRU_2
  RFU3  = TP_CHF_CPU0_DIMM2_FRU_3
  VSS64  = GND
  DQ2_A  = M_F_CPU0_SA_DQ<2>
  VSS65  = GND
  DQ3_A  = M_F_CPU0_SA_DQ<3>
  VSS66  = GND
  \dqs5_a_c||tdqs5_a_c||dqs5_a_t||tdqs5_a_t\  = M_F_CPU0_SA_DQS_DN<5>
  \dqs5_a_t||tdqs5_a_t\  = M_F_CPU0_SA_DQS_DP<5>
  VSS67  = GND
  DQ6_A  = M_F_CPU0_SA_DQ<6>
  VSS68  = GND
  DQ7_A  = M_F_CPU0_SA_DQ<7>
  VSS69  = GND
  DQ10_A  = M_F_CPU0_SA_DQ<10>
  VSS70  = GND
  DQ11_A  = M_F_CPU0_SA_DQ<11>
  VSS71  = GND
  \dqs6_a_c||tdqs6_a_c||dqs6_a_t||tdqs6_a_t\  = M_F_CPU0_SA_DQS_DN<6>
  \dqs6_a_t||tdqs6_a_t\  = M_F_CPU0_SA_DQS_DP<6>
  VSS72  = GND
  DQ14_A  = M_F_CPU0_SA_DQ<14>
  VSS73  = GND
  DQ15_A  = M_F_CPU0_SA_DQ<15>
  VSS74  = GND
  DQ18_A  = M_F_CPU0_SA_DQ<18>
  VSS75  = GND
  DQ19_A  = M_F_CPU0_SA_DQ<19>
  VSS76  = GND
  \dqs7_a_c||tdqs7_a_c\  = M_F_CPU0_SA_DQS_DN<7>
  \dqs7_a_t||tdqs7_a_t\  = M_F_CPU0_SA_DQS_DP<7>
  VSS77  = GND
  DQ22_A  = M_F_CPU0_SA_DQ<22>
  VSS78  = GND
  DQ23_A  = M_F_CPU0_SA_DQ<23>
  VSS79  = GND
  DQ26_A  = M_F_CPU0_SA_DQ<26>
  VSS80  = GND
  DQ27_A  = M_F_CPU0_SA_DQ<27>
  VSS81  = GND
  \dqs8_a_c||tdqs8_a_c\  = M_F_CPU0_SA_DQS_DN<8>
  \dqs8_a_t||tdqs8_a_t\  = M_F_CPU0_SA_DQS_DP<8>
  VSS82  = GND
  DQ30_A  = M_F_CPU0_SA_DQ<30>
  VSS83  = GND
  DQ31_A  = M_F_CPU0_SA_DQ<31>
  VSS84  = GND
  CB2_A  = M_F_CPU0_SA_CB<2>
  VSS85  = GND
  CB3_A  = M_F_CPU0_SA_CB<3>
  VSS86  = GND
  \dqs9_a_c||tdqs9_a_c\  = M_F_CPU0_SA_DQS_DN<9>
  \dqs9_a_t||tdqs9_a_t\  = M_F_CPU0_SA_DQS_DP<9>
  VSS87  = GND
  CB6_A  = M_F_CPU0_SA_CB<6>
  VSS88  = GND
  CB7_A  = M_F_CPU0_SA_CB<7>
  VSS89  = GND
  RESET_N  = RST_M_EF_CPU0_FPGA_N
  VSS90  = GND
  CS1_A_N  = M_F_CPU0_SA_CS_N<3>
  VSS91  = GND
  CA1_A  = M_F_CPU0_SA_CA<1>
  VSS92  = GND
  CA3_A  = M_F_CPU0_SA_CA<3>
  VSS93  = GND
  CA5_A  = M_F_CPU0_SA_CA<5>
  VSS94  = GND
  CK_T  = M_F_CPU0_CLK_DP<1>
  CK_C  = M_F_CPU0_CLK_DN<1>
  VSS95  = GND
  RFU4  = TP_CHF_CPU0_DIMM2_FRU_4
  CA1_B  = M_F_CPU0_SB_CA<1>
  VSS96  = GND
  CA3_B  = M_F_CPU0_SB_CA<3>
  VSS97  = GND
  CA5_B  = M_F_CPU0_SB_CA<5>
  VSS98  = GND
  PAR_B  = M_F_CPU0_SB_PAR
  VSS99  = GND
  CS1_B_N  = M_F_CPU0_SB_CS_N<3>
  VSS100  = GND
  RFU5  = TP_CHF_CPU0_DIMM2_FRU_5
  RFU6  = TP_CHF_CPU0_DIMM2_FRU_6
  VSS101  = GND
  CB6_B  = M_F_CPU0_SB_CB<6>
  VSS102  = GND
  CB7_B  = M_F_CPU0_SB_CB<7>
  VSS103  = GND
  DQS4_B_C  = M_F_CPU0_SB_DQS_DN<4>
  DQS4_B_T  = M_F_CPU0_SB_DQS_DP<4>
  VSS104  = GND
  CB2_B  = M_F_CPU0_SB_CB<2>
  VSS105  = GND
  CB3_B  = M_F_CPU0_SB_CB<3>
  VSS106  = GND
  DQ2_B  = M_F_CPU0_SB_DQ<2>
  VSS107  = GND
  DQ3_B  = M_F_CPU0_SB_DQ<3>
  VSS108  = GND
  \dqs5_b_c||tdqs5_b_c\  = M_F_CPU0_SB_DQS_DN<5>
  \dqs5_b_t||tdqs5_b_t\  = M_F_CPU0_SB_DQS_DP<5>
  VSS109  = GND
  DQ6_B  = M_F_CPU0_SB_DQ<6>
  VSS110  = GND
  DQ7_B  = M_F_CPU0_SB_DQ<7>
  VSS111  = GND
  DQ10_B  = M_F_CPU0_SB_DQ<10>
  VSS112  = GND
  DQ11_B  = M_F_CPU0_SB_DQ<11>
  VSS113  = GND
  \dqs6_b_c||tdqs6_b_c\  = M_F_CPU0_SB_DQS_DN<6>
  \dqs6_b_t||tdqs6_b_t\  = M_F_CPU0_SB_DQS_DP<6>
  VSS114  = GND
  DQ14_B  = M_F_CPU0_SB_DQ<14>
  VSS115  = GND
  DQ15_B  = M_F_CPU0_SB_DQ<15>
  VSS116  = GND
  DQ18_B  = M_F_CPU0_SB_DQ<18>
  VSS117  = GND
  DQ19_B  = M_F_CPU0_SB_DQ<19>
  VSS118  = GND
  \dqs7_b_c||tdqs7_b_c\  = M_F_CPU0_SB_DQS_DN<7>
  \dqs7_b_t||tdqs7_b_t\  = M_F_CPU0_SB_DQS_DP<7>
  VSS119  = GND
  DQ22_B  = M_F_CPU0_SB_DQ<22>
  VSS120  = GND
  DQ23_B  = M_F_CPU0_SB_DQ<23>
  VSS121  = GND
  DQ26_B  = M_F_CPU0_SB_DQ<26>
  VSS122  = GND
  DQ27_B  = M_F_CPU0_SB_DQ<27>
  VSS123  = GND
  \dqs8_b_c||tdqs8_b_c\  = M_F_CPU0_SB_DQS_DN<8>
  \dqs8_b_t||tdqs8_b_t\  = M_F_CPU0_SB_DQS_DP<8>
  VSS124  = GND
  DQ30_B  = M_F_CPU0_SB_DQ<30>
  VSS125  = GND
  DQ31_B  = M_F_CPU0_SB_DQ<31>
  VSS126  = GND
  G1  = GND
  G2  = GND
  G3  = GND

(kicad_pcb
	(version 20260206)
	(generator "pcbnew")
	(generator_version "10.0")
	(general
		(thickness 1.6)
		(legacy_teardrops no)
	)
	(paper "A4")
	(title_block
		(title "03242023_DA0F0TMBIJ0_F0T_Motherboard_J_brd_V01_OCP.brd")
		(comment 1 "Grand Teton / footprint 3198 of 6105 (J12), pads 92-137 of 291")
	)
	(layers
		(0 "F.Cu" signal "TOP")
		(4 "In1.Cu" signal "GND")
		(6 "In2.Cu" signal "IN1")
		(8 "In3.Cu" signal "GND1")
		(10 "In4.Cu" signal "IN2")
		(12 "In5.Cu" signal "GND2")
		(14 "In6.Cu" signal "IN3")
		(16 "In7.Cu" signal "GND3")
		(18 "In8.Cu" signal "VCC")
		(20 "In9.Cu" signal "VCC1")
		(22 "In10.Cu" signal "GND4")
		(24 "In11.Cu" signal "IN4")
		(26 "In12.Cu" signal "GND5")
		(28 "In13.Cu" signal "IN5")
		(30 "In14.Cu" signal "GND6")
		(32 "In15.Cu" signal "IN6")
		(34 "In16.Cu" signal "GND7")
		(2 "B.Cu" signal "BOTTOM")
		(9 "F.Adhes" user "F.Adhesive")
		(11 "B.Adhes" user "B.Adhesive")
		(13 "F.Paste" user "Package Geometry/Pastemask Top")
		(15 "B.Paste" user "Package Geometry/Pastemask Bottom")
		(5 "F.SilkS" user "Ref Des/Silkscreen Top")
		(7 "B.SilkS" user "Ref Des/Silkscreen Bottom")
		(1 "F.Mask" user "Board Geometry/Soldermask Top")
		(3 "B.Mask" user "Board Geometry/Soldermask Bottom")
		(17 "Dwgs.User" user "User.Drawings")
		(19 "Cmts.User" user "User.Comments")
		(21 "Eco1.User" user "User.Eco1")
		(23 "Eco2.User" user "User.Eco2")
		(25 "Edge.Cuts" user "Board Geometry/Outline")
		(27 "Margin" user)
		(31 "F.CrtYd" user "Package Geometry/Place Bound Top")
		(29 "B.CrtYd" user "Package Geometry/Place Bound Bottom")
		(35 "F.Fab" user "Ref Des/Assembly Top")
		(33 "B.Fab" user "Ref Des/Assembly Bottom")
	)
	(footprint ""
		(layer "F.Cu")
		(at 423.890948 -258.091686)
		(property "Reference" "J12"
			(at -3.683 -81.702148 0)
			(unlocked yes)
			(layer "F.SilkS")
			(effects
				(font
					(size 0.7874 0.5842)
					(thickness 0.1524)
				)
				(justify left)
			)
		)
		(property "Value" ""
			(at 0 0 0)
			(layer "F.Fab")
			(effects
				(font
					(size 1.27 1.27)
				)
			)
		)
		(duplicate_pad_numbers_are_jumpers no)
		(pad "92" smd rect
			(at -2.050034 19.12493 270)
			(size 0.519938 1.4986)
			(layers "F.Cu" "F.Mask" "F.Paste")
			(net "GND")
		)
		(pad "93" smd rect
			(at -2.050034 19.975068 270)
			(size 0.519938 1.4986)
			(layers "F.Cu" "F.Mask" "F.Paste")
			(net "M_F_CPU0_SB_DQS_DP<9>")
		)
		(pad "94" smd rect
			(at -2.050034 20.824952 270)
			(size 0.519938 1.4986)
			(layers "F.Cu" "F.Mask" "F.Paste")
			(net "M_F_CPU0_SB_DQS_DN<9>")
		)
		(pad "95" smd rect
			(at -2.050034 21.67509 270)
			(size 0.519938 1.4986)
			(layers "F.Cu" "F.Mask" "F.Paste")
			(net "GND")
		)
		(pad "96" smd rect
			(at -2.050034 22.524974 270)
			(size 0.519938 1.4986)
			(layers "F.Cu" "F.Mask" "F.Paste")
			(net "M_F_CPU0_SB_CB<0>")
		)
		(pad "97" smd rect
			(at -2.050034 23.375112 270)
			(size 0.519938 1.4986)
			(layers "F.Cu" "F.Mask" "F.Paste")
			(net "GND")
		)
		(pad "98" smd rect
			(at -2.050034 24.224996 270)
			(size 0.519938 1.4986)
			(layers "F.Cu" "F.Mask" "F.Paste")
			(net "M_F_CPU0_SB_CB<1>")
		)
		(pad "99" smd rect
			(at -2.050034 25.07488 270)
			(size 0.519938 1.4986)
			(layers "F.Cu" "F.Mask" "F.Paste")
			(net "GND")
		)
		(pad "100" smd rect
			(at -2.050034 25.925018 270)
			(size 0.519938 1.4986)
			(layers "F.Cu" "F.Mask" "F.Paste")
			(net "M_F_CPU0_SB_DQ<0>")
		)
		(pad "101" smd rect
			(at -2.050034 26.774902 270)
			(size 0.519938 1.4986)
			(layers "F.Cu" "F.Mask" "F.Paste")
			(net "GND")
		)
		(pad "102" smd rect
			(at -2.050034 27.62504 270)
			(size 0.519938 1.4986)
			(layers "F.Cu" "F.Mask" "F.Paste")
			(net "M_F_CPU0_SB_DQ<1>")
		)
		(pad "103" smd rect
			(at -2.050034 28.474924 270)
			(size 0.519938 1.4986)
			(layers "F.Cu" "F.Mask" "F.Paste")
			(net "GND")
		)
		(pad "104" smd rect
			(at -2.050034 29.325062 270)
			(size 0.519938 1.4986)
			(layers "F.Cu" "F.Mask" "F.Paste")
			(net "M_F_CPU0_SB_DQS_DP<0>")
		)
		(pad "105" smd rect
			(at -2.050034 30.174946 270)
			(size 0.519938 1.4986)
			(layers "F.Cu" "F.Mask" "F.Paste")
			(net "M_F_CPU0_SB_DQS_DN<0>")
		)
		(pad "106" smd rect
			(at -2.050034 31.025084 270)
			(size 0.519938 1.4986)
			(layers "F.Cu" "F.Mask" "F.Paste")
			(net "GND")
		)
		(pad "107" smd rect
			(at -2.050034 31.874968 270)
			(size 0.519938 1.4986)
			(layers "F.Cu" "F.Mask" "F.Paste")
			(net "M_F_CPU0_SB_DQ<4>")
		)
		(pad "108" smd rect
			(at -2.050034 32.725106 270)
			(size 0.519938 1.4986)
			(layers "F.Cu" "F.Mask" "F.Paste")
			(net "GND")
		)
		(pad "109" smd rect
			(at -2.050034 33.57499 270)
			(size 0.519938 1.4986)
			(layers "F.Cu" "F.Mask" "F.Paste")
			(net "M_F_CPU0_SB_DQ<5>")
		)
		(pad "110" smd rect
			(at -2.050034 34.425128 270)
			(size 0.519938 1.4986)
			(layers "F.Cu" "F.Mask" "F.Paste")
			(net "GND")
		)
		(pad "111" smd rect
			(at -2.050034 35.275012 270)
			(size 0.519938 1.4986)
			(layers "F.Cu" "F.Mask" "F.Paste")
			(net "M_F_CPU0_SB_DQ<8>")
		)
		(pad "112" smd rect
			(at -2.050034 36.124896 270)
			(size 0.519938 1.4986)
			(layers "F.Cu" "F.Mask" "F.Paste")
			(net "GND")
		)
		(pad "113" smd rect
			(at -2.050034 36.975034 270)
			(size 0.519938 1.4986)
			(layers "F.Cu" "F.Mask" "F.Paste")
			(net "M_F_CPU0_SB_DQ<9>")
		)
		(pad "114" smd rect
			(at -2.050034 37.824918 270)
			(size 0.519938 1.4986)
			(layers "F.Cu" "F.Mask" "F.Paste")
			(net "GND")
		)
		(pad "115" smd rect
			(at -2.050034 38.675056 270)
			(size 0.519938 1.4986)
			(layers "F.Cu" "F.Mask" "F.Paste")
			(net "M_F_CPU0_SB_DQS_DP<1>")
		)
		(pad "116" smd rect
			(at -2.050034 39.52494 270)
			(size 0.519938 1.4986)
			(layers "F.Cu" "F.Mask" "F.Paste")
			(net "M_F_CPU0_SB_DQS_DN<1>")
		)
		(pad "117" smd rect
			(at -2.050034 40.375078 270)
			(size 0.519938 1.4986)
			(layers "F.Cu" "F.Mask" "F.Paste")
			(net "GND")
		)
		(pad "118" smd rect
			(at -2.050034 41.224962 270)
			(size 0.519938 1.4986)
			(layers "F.Cu" "F.Mask" "F.Paste")
			(net "M_F_CPU0_SB_DQ<12>")
		)
		(pad "119" smd rect
			(at -2.050034 42.0751 270)
			(size 0.519938 1.4986)
			(layers "F.Cu" "F.Mask" "F.Paste")
			(net "GND")
		)
		(pad "120" smd rect
			(at -2.050034 42.924984 270)
			(size 0.519938 1.4986)
			(layers "F.Cu" "F.Mask" "F.Paste")
			(net "M_F_CPU0_SB_DQ<13>")
		)
		(pad "121" smd rect
			(at -2.050034 43.775122 270)
			(size 0.519938 1.4986)
			(layers "F.Cu" "F.Mask" "F.Paste")
			(net "GND")
		)
		(pad "122" smd rect
			(at -2.050034 44.625006 270)
			(size 0.519938 1.4986)
			(layers "F.Cu" "F.Mask" "F.Paste")
			(net "M_F_CPU0_SB_DQ<16>")
		)
		(pad "123" smd rect
			(at -2.050034 45.47489 270)
			(size 0.519938 1.4986)
			(layers "F.Cu" "F.Mask" "F.Paste")
			(net "GND")
		)
		(pad "124" smd rect
			(at -2.050034 46.325028 270)
			(size 0.519938 1.4986)
			(layers "F.Cu" "F.Mask" "F.Paste")
			(net "M_F_CPU0_SB_DQ<17>")
		)
		(pad "125" smd rect
			(at -2.050034 47.174912 270)
			(size 0.519938 1.4986)
			(layers "F.Cu" "F.Mask" "F.Paste")
			(net "GND")
		)
		(pad "126" smd rect
			(at -2.050034 48.02505 270)
			(size 0.519938 1.4986)
			(layers "F.Cu" "F.Mask" "F.Paste")
			(net "M_F_CPU0_SB_DQS_DP<2>")
		)
		(pad "127" smd rect
			(at -2.050034 48.874934 270)
			(size 0.519938 1.4986)
			(layers "F.Cu" "F.Mask" "F.Paste")
			(net "M_F_CPU0_SB_DQS_DN<2>")
		)
		(pad "128" smd rect
			(at -2.050034 49.725072 270)
			(size 0.519938 1.4986)
			(layers "F.Cu" "F.Mask" "F.Paste")
			(net "GND")
		)
		(pad "129" smd rect
			(at -2.050034 50.574956 270)
			(size 0.519938 1.4986)
			(layers "F.Cu" "F.Mask" "F.Paste")
			(net "M_F_CPU0_SB_DQ<20>")
		)
		(pad "130" smd rect
			(at -2.050034 51.425094 270)
			(size 0.519938 1.4986)
			(layers "F.Cu" "F.Mask" "F.Paste")
			(net "GND")
		)
		(pad "131" smd rect
			(at -2.050034 52.274978 270)
			(size 0.519938 1.4986)
			(layers "F.Cu" "F.Mask" "F.Paste")
			(net "M_F_CPU0_SB_DQ<21>")
		)
		(pad "132" smd rect
			(at -2.050034 53.125116 270)
			(size 0.519938 1.4986)
			(layers "F.Cu" "F.Mask" "F.Paste")
			(net "GND")
		)
		(pad "133" smd rect
			(at -2.050034 53.975 270)
			(size 0.519938 1.4986)
			(layers "F.Cu" "F.Mask" "F.Paste")
			(net "M_F_CPU0_SB_DQ<24>")
		)
		(pad "134" smd rect
			(at -2.050034 54.824884 270)
			(size 0.519938 1.4986)
			(layers "F.Cu" "F.Mask" "F.Paste")
			(net "GND")
		)
		(pad "135" smd rect
			(at -2.050034 55.675022 270)
			(size 0.519938 1.4986)
			(layers "F.Cu" "F.Mask" "F.Paste")
			(net "M_F_CPU0_SB_DQ<25>")
		)
		(pad "136" smd rect
			(at -2.050034 56.524906 270)
			(size 0.519938 1.4986)
			(layers "F.Cu" "F.Mask" "F.Paste")
			(net "GND")
		)
		(pad "137" smd rect
			(at -2.050034 57.375044 270)
			(size 0.519938 1.4986)
			(layers "F.Cu" "F.Mask" "F.Paste")
			(net "M_F_CPU0_SB_DQS_DP<3>")
		)
	)
)
